# T6G (Grand Teton) — schematic netlist excerpt (pin names and nets, part order shuffled) for the footprints in the layout excerpt that follows; sources: Cadence DE-HDL packaged netlist, KiCad conversion of 04192023_DAF0TMB3IC0_F0TG_MB_C_brd_V02_OCP.brd

R667  Q_RES  49.9 1% CHIP  pkg 0201LF  page 276 : A = SMB_RT_CPU0_P0_ROM_MUX_1D_SDA ; B = SMB_RT_CPU0_P0_ROM_MUX_1D_R_SDA
PC8005  Q_CAP  22UF 16V 20% X6S  pkg C0805  page 208 : A = SW_P12V_AUX_PVDD11_S3_P0_FLT ; B = GND
PC337  Q_CAPP  470UF 2.5V 20% SPCAP  pkg SMLF  page 215 : A = PVDDCR_SOC_P1 ; B = GND

(kicad_pcb
	(version 20260206)
	(generator "pcbnew")
	(generator_version "10.0")
	(general
		(thickness 1.6)
		(legacy_teardrops no)
	)
	(paper "A4")
	(title_block
		(title "04192023_DAF0TMB3IC0_F0TG_MB_C_brd_V02_OCP.brd")
		(comment 1 "Grand Teton / footprints 6541-6543 of 8354")
	)
	(layers
		(0 "F.Cu" signal "TOP")
		(4 "In1.Cu" signal "GND")
		(6 "In2.Cu" signal "IN1")
		(8 "In3.Cu" signal "GND1")
		(10 "In4.Cu" signal "IN2")
		(12 "In5.Cu" signal "GND2")
		(14 "In6.Cu" signal "IN3")
		(16 "In7.Cu" signal "GND3")
		(18 "In8.Cu" signal "VCC")
		(20 "In9.Cu" signal "VCC1")
		(22 "In10.Cu" signal "GND4")
		(24 "In11.Cu" signal "IN4")
		(26 "In12.Cu" signal "GND5")
		(28 "In13.Cu" signal "IN5")
		(30 "In14.Cu" signal "GND6")
		(32 "In15.Cu" signal "IN6")
		(34 "In16.Cu" signal "GND7")
		(2 "B.Cu" signal "BOTTOM")
		(9 "F.Adhes" user "F.Adhesive")
		(11 "B.Adhes" user "B.Adhesive")
		(13 "F.Paste" user "Package Geometry/Pastemask Top")
		(15 "B.Paste" user "Package Geometry/Pastemask Bottom")
		(5 "F.SilkS" user "Ref Des/Silkscreen Top")
		(7 "B.SilkS" user "Ref Des/Silkscreen Bottom")
		(1 "F.Mask" user "Board Geometry/Soldermask Top")
		(3 "B.Mask" user "Board Geometry/Soldermask Bottom")
		(17 "Dwgs.User" user "User.Drawings")
		(19 "Cmts.User" user "User.Comments")
		(21 "Eco1.User" user "User.Eco1")
		(23 "Eco2.User" user "User.Eco2")
		(25 "Edge.Cuts" user "Board Geometry/Outline")
		(27 "Margin" user)
		(31 "F.CrtYd" user "Package Geometry/Place Bound Top")
		(29 "B.CrtYd" user "Package Geometry/Place Bound Bottom")
		(35 "F.Fab" user "Ref Des/Assembly Top")
		(33 "B.Fab" user "Ref Des/Assembly Bottom")
	)
	(footprint ""
		(layer "B.Cu")
		(at 123.126754 -171.910248 90)
		(property "Reference" "PC337"
			(at 5.774436 1.227074 270)
			(unlocked yes)
			(layer "B.SilkS")
			(effects
				(font
					(size 0.7874 0.5842)
					(thickness 0.1524)
				)
				(justify left mirror)
			)
		)
		(property "Value" ""
			(at 0 0 90)
			(layer "B.Fab")
			(effects
				(font
					(size 1.27 1.27)
				)
				(justify mirror)
			)
		)
		(duplicate_pad_numbers_are_jumpers no)
		(fp_line
			(start 4.533392 -2.249932)
			(end -4.533392 -2.249932)
			(stroke
				(width 0.1524)
				(type default)
			)
			(layer "B.SilkS")
		)
		(fp_line
			(start -4.533392 -2.249932)
			(end -4.533392 2.249932)
			(stroke
				(width 0.1524)
				(type default)
			)
			(layer "B.SilkS")
		)
		(fp_line
			(start 4.533392 2.249932)
			(end 4.533392 -2.249932)
			(stroke
				(width 0.1524)
				(type default)
			)
			(layer "B.SilkS")
		)
		(fp_line
			(start -4.533392 2.249932)
			(end 4.533392 2.249932)
			(stroke
				(width 0.1524)
				(type default)
			)
			(layer "B.SilkS")
		)
		(fp_rect
			(start 4.533392 -2.326132)
			(end 5.39242 2.326132)
			(stroke
				(width 0)
				(type default)
			)
			(fill yes)
			(layer "B.SilkS")
		)
		(fp_line
			(start 3.750056 -2.249932)
			(end -3.750056 -2.249932)
			(stroke
				(width 0.1)
				(type default)
			)
			(layer "B.Fab")
		)
		(fp_line
			(start -3.750056 -2.249932)
			(end -3.750056 2.249932)
			(stroke
				(width 0.1)
				(type default)
			)
			(layer "B.Fab")
		)
		(fp_line
			(start 3.750056 2.249932)
			(end 3.750056 -2.249932)
			(stroke
				(width 0.1)
				(type default)
			)
			(layer "B.Fab")
		)
		(fp_line
			(start -3.750056 2.249932)
			(end 3.750056 2.249932)
			(stroke
				(width 0.1)
				(type default)
			)
			(layer "B.Fab")
		)
		(fp_text user "+"
			(at 6.322314 0.786384 0)
			(unlocked yes)
			(layer "B.SilkS")
			(effects
				(font
					(size 1.905 1.4224)
					(thickness 0.1524)
				)
				(justify left mirror)
			)
		)
		(fp_text user "-"
			(at -4.732274 1.216152 90)
			(unlocked yes)
			(layer "B.SilkS")
			(effects
				(font
					(size 1.905 1.4224)
					(thickness 0.1524)
				)
				(justify left mirror)
			)
		)
		(fp_text user "-"
			(at -4.8514 -0.14605 90)
			(unlocked yes)
			(layer "B.Fab")
			(effects
				(font
					(size 1.905 1.4224)
					(thickness 0.1524)
				)
				(justify left mirror)
			)
		)
		(fp_text user "+"
			(at 6.322314 0.786384 0)
			(unlocked yes)
			(layer "B.Fab")
			(effects
				(font
					(size 1.905 1.4224)
					(thickness 0.1524)
				)
				(justify left mirror)
			)
		)
		(pad "1" smd rect
			(at 3.199892 0 270)
			(size 2.413 2.8194)
			(layers "B.Cu" "B.Mask" "B.Paste")
			(net "PVDDCR_SOC_P1")
		)
		(pad "2" smd rect
			(at -3.199892 0 270)
			(size 2.413 2.8194)
			(layers "B.Cu" "B.Mask" "B.Paste")
			(net "GND")
		)
	)
	(footprint ""
		(layer "B.Cu")
		(at 425.896532 -358.570276)
		(property "Reference" "PC8005"
			(at 0 0 0)
			(layer "B.SilkS")
			(hide yes)
			(effects
				(font
					(size 1.27 1.27)
				)
				(justify mirror)
			)
		)
		(property "Value" ""
			(at 0 0 0)
			(layer "B.Fab")
			(effects
				(font
					(size 1.27 1.27)
				)
				(justify mirror)
			)
		)
		(duplicate_pad_numbers_are_jumpers no)
		(fp_line
			(start -1.524 -0.762)
			(end -1.524 0.762)
			(stroke
				(width 0.1524)
				(type default)
			)
			(layer "B.SilkS")
		)
		(fp_line
			(start -1.524 0.762)
			(end 1.524 0.762)
			(stroke
				(width 0.1524)
				(type default)
			)
			(layer "B.SilkS")
		)
		(fp_line
			(start 1.524 -0.762)
			(end -1.524 -0.762)
			(stroke
				(width 0.1524)
				(type default)
			)
			(layer "B.SilkS")
		)
		(fp_line
			(start 1.524 0.762)
			(end 1.524 -0.762)
			(stroke
				(width 0.1524)
				(type default)
			)
			(layer "B.SilkS")
		)
		(fp_line
			(start -1.1049 -0.724916)
			(end 1.1049 -0.724916)
			(stroke
				(width 0.1)
				(type default)
			)
			(layer "B.Fab")
		)
		(fp_line
			(start -1.1049 0.724916)
			(end -1.1049 -0.724916)
			(stroke
				(width 0.1)
				(type default)
			)
			(layer "B.Fab")
		)
		(fp_line
			(start 1.1049 -0.724916)
			(end 1.1049 0.724916)
			(stroke
				(width 0.1)
				(type default)
			)
			(layer "B.Fab")
		)
		(fp_line
			(start 1.1049 0.724916)
			(end -1.1049 0.724916)
			(stroke
				(width 0.1)
				(type default)
			)
			(layer "B.Fab")
		)
		(pad "1" smd rect
			(at 0.889 0)
			(size 1.016 1.27)
			(layers "B.Cu" "B.Mask" "B.Paste")
			(net "SW_P12V_AUX_PVDD11_S3_P0_FLT")
		)
		(pad "2" smd rect
			(at -0.889 0)
			(size 1.016 1.27)
			(layers "B.Cu" "B.Mask" "B.Paste")
			(net "GND")
		)
	)
	(footprint ""
		(layer "B.Cu")
		(at 301.388272 -425.498768 180)
		(property "Reference" "R667"
			(at 0 0 0)
			(layer "B.SilkS")
			(hide yes)
			(effects
				(font
					(size 1.27 1.27)
				)
				(justify mirror)
			)
		)
		(property "Value" ""
			(at 0 0 0)
			(layer "B.Fab")
			(effects
				(font
					(size 1.27 1.27)
				)
				(justify mirror)
			)
		)
		(duplicate_pad_numbers_are_jumpers no)
		(fp_line
			(start 0.32512 0.175006)
			(end 0.32512 -0.175006)
			(stroke
				(width 0.1)
				(type default)
			)
			(layer "B.Fab")
		)
		(fp_line
			(start 0.32512 -0.175006)
			(end -0.32512 -0.175006)
			(stroke
				(width 0.1)
				(type default)
			)
			(layer "B.Fab")
		)
		(fp_line
			(start -0.32512 0.175006)
			(end 0.32512 0.175006)
			(stroke
				(width 0.1)
				(type default)
			)
			(layer "B.Fab")
		)
		(fp_line
			(start -0.32512 -0.175006)
			(end -0.32512 0.175006)
			(stroke
				(width 0.1)
				(type default)
			)
			(layer "B.Fab")
		)
		(pad "1" smd rect
			(at 0.2667 0)
			(size 0.3048 0.381)
			(layers "B.Cu" "B.Mask" "B.Paste")
			(net "SMB_RT_CPU0_P0_ROM_MUX_1D_SDA")
		)
		(pad "2" smd rect
			(at -0.2667 0 180)
			(size 0.3048 0.381)
			(layers "B.Cu" "B.Mask" "B.Paste")
			(net "SMB_RT_CPU0_P0_ROM_MUX_1D_R_SDA")
		)
	)
)
